(kicad_pcb
	(version 20241229)
	(generator "pcbnew")
	(generator_version "9.0")
	(general
		(thickness 1.294)
		(legacy_teardrops no)
	)
	(paper "A3")
	(title_block
		(title "Kintex 410T devboard")
		(date "2024-04-03")
		(rev "1.1.2")
		(comment 9 "footprints 212-217 of 975")
	)
	(layers
		(0 "F.Cu" mixed)
		(4 "In1.Cu" power)
		(6 "In2.Cu" power)
		(8 "In3.Cu" mixed)
		(10 "In4.Cu" power)
		(12 "In5.Cu" mixed)
		(14 "In6.Cu" power)
		(16 "In7.Cu" mixed)
		(18 "In8.Cu" power)
		(2 "B.Cu" mixed)
		(9 "F.Adhes" user "F.Adhesive")
		(11 "B.Adhes" user "B.Adhesive")
		(13 "F.Paste" user)
		(15 "B.Paste" user)
		(5 "F.SilkS" user "F.Silkscreen")
		(7 "B.SilkS" user "B.Silkscreen")
		(1 "F.Mask" user)
		(3 "B.Mask" user)
		(17 "Dwgs.User" user "User.Drawings")
		(19 "Cmts.User" user "User.Comments")
		(21 "Eco1.User" user "User.Eco1")
		(23 "Eco2.User" user "User.Eco2")
		(25 "Edge.Cuts" user)
		(27 "Margin" user)
		(31 "F.CrtYd" user "F.Courtyard")
		(29 "B.CrtYd" user "B.Courtyard")
		(35 "F.Fab" user)
		(33 "B.Fab" user)
	)
	(footprint "antmicro-footprints:SC70-3"
		(layer "F.Cu")
		(at 258.4 83.8)
		(property "Reference" "Q8"
			(at -1.6 1.1 90)
			(layer "F.SilkS")
			(effects
				(font
					(size 0.7 0.7)
					(thickness 0.15)
				)
				(justify left bottom)
			)
		)
		(property "Value" "BSS138PW"
			(at 0 2.3 0)
			(layer "F.Fab")
			(effects
				(font
					(size 0.7 0.7)
					(thickness 0.15)
				)
				(justify left bottom)
			)
		)
		(property "Description" "Power MOSFET, N Channel, 60 V, 320 mA, 0.9 ohm, SOT-323, Surface Mount"
			(at 0 0 0)
			(layer "F.Fab")
			(hide yes)
			(effects
				(font
					(size 1.27 1.27)
					(thickness 0.15)
				)
			)
		)
		(property "Author" "Antmicro"
			(at 0 0 0)
			(layer "F.Fab")
			(hide yes)
			(effects
				(font
					(size 1 1)
					(thickness 0.15)
				)
			)
		)
		(property "License" "Apache-2.0"
			(at 0 0 0)
			(layer "F.Fab")
			(hide yes)
			(effects
				(font
					(size 1 1)
					(thickness 0.15)
				)
			)
		)
		(property "MPN" "BSS138PW"
			(at 0 0 0)
			(layer "F.Fab")
			(hide yes)
			(effects
				(font
					(size 1 1)
					(thickness 0.15)
				)
			)
		)
		(property "Manufacturer" "Nexperia"
			(at 0 0 0)
			(layer "F.Fab")
			(hide yes)
			(effects
				(font
					(size 1 1)
					(thickness 0.15)
				)
			)
		)
		(sheetname "User GPIO + LED + button + DIP switch")
		(sheetfile "user-gpio.kicad_sch")
		(attr smd)
		(fp_line
			(start -0.3 -1)
			(end 0.627 -0.999)
			(stroke
				(width 0.15)
				(type solid)
			)
			(layer "F.SilkS")
		)
		(fp_line
			(start -0.3 1)
			(end 0.627 1.001)
			(stroke
				(width 0.15)
				(type solid)
			)
			(layer "F.SilkS")
		)
		(fp_line
			(start 0.627 -0.6)
			(end 0.627 -0.999)
			(stroke
				(width 0.15)
				(type solid)
			)
			(layer "F.SilkS")
		)
		(fp_line
			(start 0.627 0.6)
			(end 0.627 1.001)
			(stroke
				(width 0.15)
				(type solid)
			)
			(layer "F.SilkS")
		)
		(fp_line
			(start -1.4 1)
			(end -1.4 -1)
			(stroke
				(width 0.05)
				(type solid)
			)
			(layer "F.CrtYd")
		)
		(fp_line
			(start -0.9 -1.3)
			(end -0.9 -1)
			(stroke
				(width 0.05)
				(type solid)
			)
			(layer "F.CrtYd")
		)
		(fp_line
			(start -0.9 -1.3)
			(end 0.9 -1.3)
			(stroke
				(width 0.05)
				(type solid)
			)
			(layer "F.CrtYd")
		)
		(fp_line
			(start -0.9 -1)
			(end -1.4 -1)
			(stroke
				(width 0.05)
				(type solid)
			)
			(layer "F.CrtYd")
		)
		(fp_line
			(start -0.9 1)
			(end -1.4 1)
			(stroke
				(width 0.05)
				(type solid)
			)
			(layer "F.CrtYd")
		)
		(fp_line
			(start -0.9 1.3)
			(end -0.9 1)
			(stroke
				(width 0.05)
				(type solid)
			)
			(layer "F.CrtYd")
		)
		(fp_line
			(start 0.9 -1.3)
			(end 0.9 -0.4)
			(stroke
				(width 0.05)
				(type solid)
			)
			(layer "F.CrtYd")
		)
		(fp_line
			(start 0.9 -0.4)
			(end 1.4 -0.4)
			(stroke
				(width 0.05)
				(type solid)
			)
			(layer "F.CrtYd")
		)
		(fp_line
			(start 0.9 0.4)
			(end 0.9 1.3)
			(stroke
				(width 0.05)
				(type solid)
			)
			(layer "F.CrtYd")
		)
		(fp_line
			(start 0.9 1.3)
			(end -0.9 1.3)
			(stroke
				(width 0.05)
				(type solid)
			)
			(layer "F.CrtYd")
		)
		(fp_line
			(start 1.4 -0.4)
			(end 1.4 0.4)
			(stroke
				(width 0.05)
				(type solid)
			)
			(layer "F.CrtYd")
		)
		(fp_line
			(start 1.4 0.4)
			(end 0.9 0.4)
			(stroke
				(width 0.05)
				(type solid)
			)
			(layer "F.CrtYd")
		)
		(fp_rect
			(start -0.623 -0.999)
			(end 0.627 1.001)
			(stroke
				(width 0.15)
				(type solid)
			)
			(fill no)
			(layer "F.Fab")
		)
		(pad "1" smd rect
			(at -1.051 -0.65 90)
			(size 0.6 0.6)
			(layers "F.Cu" "F.Mask" "F.Paste")
			(net 1299 "/USER_IO.LED_GREEN0")
			(pinfunction "G")
			(pintype "passive")
		)
		(pad "2" smd rect
			(at -1.051 0.65 90)
			(size 0.6 0.6)
			(layers "F.Cu" "F.Mask" "F.Paste")
			(net 1 "GND")
			(pinfunction "S")
			(pintype "passive")
		)
		(pad "3" smd rect
			(at 1.05 0 90)
			(size 0.6 0.6)
			(layers "F.Cu" "F.Mask" "F.Paste")
			(net 772 "Net-(D18-C)")
			(pinfunction "D")
			(pintype "passive")
		)
	)
	(footprint "antmicro-footprints:R_0402_1005Metric"
		(layer "F.Cu")
		(at 235.925 110.6 180)
		(descr "Resistor SMD 0402")
		(tags "resistor SMD 0402")
		(property "Reference" "R93"
			(at -0.8 -0.375 180)
			(layer "F.SilkS")
			(effects
				(font
					(size 0.7 0.7)
					(thickness 0.15)
				)
				(justify left bottom)
			)
		)
		(property "Value" "R_10k_0402"
			(at 0 1.4 180)
			(layer "F.Fab")
			(effects
				(font
					(size 0.7 0.7)
					(thickness 0.15)
				)
				(justify left bottom)
			)
		)
		(property "Description" "SMD Chip Resistor, 10 kohm, ± 1%, 62.5 mW, 0402 [1005 Metric], Thick Film, General Purpose"
			(at 0 0 180)
			(layer "F.Fab")
			(hide yes)
			(effects
				(font
					(size 1.27 1.27)
					(thickness 0.15)
				)
			)
		)
		(property "Author" "Antmicro"
			(at 471.85 221.2 0)
			(layer "F.Fab")
			(hide yes)
			(effects
				(font
					(size 1 1)
					(thickness 0.15)
				)
			)
		)
		(property "License" "Apache-2.0"
			(at 471.85 221.2 0)
			(layer "F.Fab")
			(hide yes)
			(effects
				(font
					(size 1 1)
					(thickness 0.15)
				)
			)
		)
		(property "MPN" "CR0402-FX-1002GLF"
			(at 471.85 221.2 0)
			(layer "F.Fab")
			(hide yes)
			(effects
				(font
					(size 1 1)
					(thickness 0.15)
				)
			)
		)
		(property "Manufacturer" "Bourns"
			(at 471.85 221.2 0)
			(layer "F.Fab")
			(hide yes)
			(effects
				(font
					(size 1 1)
					(thickness 0.15)
				)
			)
		)
		(property "Tolerance" "1%"
			(at 471.85 221.2 0)
			(layer "F.Fab")
			(hide yes)
			(effects
				(font
					(size 1 1)
					(thickness 0.15)
				)
			)
		)
		(property "Val" "10k"
			(at 471.85 221.2 0)
			(layer "F.Fab")
			(hide yes)
			(effects
				(font
					(size 1 1)
					(thickness 0.15)
				)
			)
		)
		(sheetname "SPI Flash + SD Card")
		(sheetfile "spi-flash.kicad_sch")
		(attr smd)
		(fp_rect
			(start -0.925 -0.47)
			(end 0.925 0.47)
			(stroke
				(width 0.05)
				(type default)
			)
			(fill no)
			(layer "F.CrtYd")
		)
		(fp_rect
			(start -0.5 -0.25)
			(end 0.5 0.25)
			(stroke
				(width 0.15)
				(type solid)
			)
			(fill no)
			(layer "F.Fab")
		)
		(pad "1" smd roundrect
			(at -0.48 0 180)
			(size 0.59 0.64)
			(layers "F.Cu" "F.Mask" "F.Paste")
			(roundrect_rratio 0.25)
			(net 417 "/FPGA Bank 16 & 17/USR_FLASH_1.DQ3")
			(pintype "passive")
		)
		(pad "2" smd roundrect
			(at 0.48 0 180)
			(size 0.59 0.64)
			(layers "F.Cu" "F.Mask" "F.Paste")
			(roundrect_rratio 0.25)
			(net 3 "VCC_USR_B")
			(pintype "passive")
		)
	)
	(footprint "antmicro-footprints:R_0402_1005Metric"
		(layer "F.Cu")
		(at 225.025 118.5)
		(descr "Resistor SMD 0402")
		(tags "resistor SMD 0402")
		(property "Reference" "R74"
			(at -2.975 0.4 0)
			(layer "F.SilkS")
			(effects
				(font
					(size 0.7 0.7)
					(thickness 0.15)
				)
				(justify left bottom)
			)
		)
		(property "Value" "R_0R_0402"
			(at 0 1.4 0)
			(layer "F.Fab")
			(effects
				(font
					(size 0.7 0.7)
					(thickness 0.15)
				)
				(justify left bottom)
			)
		)
		(property "Description" "SMD Chip Resistor, Jumper, 0 ohm, 100 mW, 0402 [1005 Metric], Thick Film, General Purpose"
			(at 0 0 0)
			(layer "F.Fab")
			(hide yes)
			(effects
				(font
					(size 1.27 1.27)
					(thickness 0.15)
				)
			)
		)
		(property "Author" "Antmicro"
			(at 0 0 0)
			(layer "F.Fab")
			(hide yes)
			(effects
				(font
					(size 1 1)
					(thickness 0.15)
				)
			)
		)
		(property "Current" "1A"
			(at 0 0 0)
			(layer "F.Fab")
			(hide yes)
			(effects
				(font
					(size 1 1)
					(thickness 0.15)
				)
			)
		)
		(property "License" "Apache-2.0"
			(at 0 0 0)
			(layer "F.Fab")
			(hide yes)
			(effects
				(font
					(size 1 1)
					(thickness 0.15)
				)
			)
		)
		(property "MPN" "ERJ2GE0R00X"
			(at 0 0 0)
			(layer "F.Fab")
			(hide yes)
			(effects
				(font
					(size 1 1)
					(thickness 0.15)
				)
			)
		)
		(property "Manufacturer" "Panasonic"
			(at 0 0 0)
			(layer "F.Fab")
			(hide yes)
			(effects
				(font
					(size 1 1)
					(thickness 0.15)
				)
			)
		)
		(property "Tolerance" ""
			(at 0 0 0)
			(layer "F.Fab")
			(hide yes)
			(effects
				(font
					(size 1 1)
					(thickness 0.15)
				)
			)
		)
		(property "Val" "0R"
			(at 0 0 0)
			(layer "F.Fab")
			(hide yes)
			(effects
				(font
					(size 1 1)
					(thickness 0.15)
				)
			)
		)
		(sheetname "SPI Flash + SD Card")
		(sheetfile "spi-flash.kicad_sch")
		(attr smd)
		(fp_rect
			(start -0.925 -0.47)
			(end 0.925 0.47)
			(stroke
				(width 0.05)
				(type default)
			)
			(fill no)
			(layer "F.CrtYd")
		)
		(fp_rect
			(start -0.5 -0.25)
			(end 0.5 0.25)
			(stroke
				(width 0.15)
				(type solid)
			)
			(fill no)
			(layer "F.Fab")
		)
		(pad "1" smd roundrect
			(at -0.48 0)
			(size 0.59 0.64)
			(layers "F.Cu" "F.Mask" "F.Paste")
			(roundrect_rratio 0.25)
			(net 75 "/FPGA Bank 14 & 15/SYSTEM_FLASH.~{CS}")
			(pintype "passive")
		)
		(pad "2" smd roundrect
			(at 0.48 0)
			(size 0.59 0.64)
			(layers "F.Cu" "F.Mask" "F.Paste")
			(roundrect_rratio 0.25)
			(net 894 "/SPI Flash + SD Card/SYSTEM_FLASH_~{CS}")
			(pintype "passive")
		)
	)
	(footprint "antmicro-footprints:TP_SMD_0.75mm"
		(layer "F.Cu")
		(at 174.16 81.1308 180)
		(property "Reference" "TP1"
			(at -0.34 0.3308 270)
			(layer "F.SilkS")
			(effects
				(font
					(size 0.7 0.7)
					(thickness 0.15)
				)
				(justify left bottom)
			)
		)
		(property "Value" "TP_0.75mm_SMD"
			(at 0 1.2 180)
			(layer "F.Fab")
			(effects
				(font
					(size 0.7 0.7)
					(thickness 0.15)
				)
				(justify left bottom)
			)
		)
		(property "Description" "SMT test point"
			(at 0 0 180)
			(layer "F.Fab")
			(hide yes)
			(effects
				(font
					(size 1.27 1.27)
					(thickness 0.15)
				)
			)
		)
		(property "Author" "Antmicro"
			(at 348.32 162.2616 0)
			(layer "F.Fab")
			(hide yes)
			(effects
				(font
					(size 1 1)
					(thickness 0.15)
				)
			)
		)
		(property "License" "Apache-2.0"
			(at 348.32 162.2616 0)
			(layer "F.Fab")
			(hide yes)
			(effects
				(font
					(size 1 1)
					(thickness 0.15)
				)
			)
		)
		(property "MPN" ""
			(at 348.32 162.2616 0)
			(layer "F.Fab")
			(hide yes)
			(effects
				(font
					(size 1 1)
					(thickness 0.15)
				)
			)
		)
		(property "Manufacturer" ""
			(at 348.32 162.2616 0)
			(layer "F.Fab")
			(hide yes)
			(effects
				(font
					(size 1 1)
					(thickness 0.15)
				)
			)
		)
		(sheetname "FMC+ HSPC")
		(sheetfile "fmc-hspc.kicad_sch")
		(attr exclude_from_pos_files)
		(pad "1" smd circle
			(at 0 0 180)
			(size 0.75 0.75)
			(layers "F.Cu" "F.Mask")
			(net 194 "Net-(J18A-VREF_A_M2C)")
			(pinfunction "1")
			(pintype "passive")
		)
	)
	(footprint "antmicro-footprints:Nexperia_SOD128"
		(layer "F.Cu")
		(at 188.825 187.699)
		(property "Reference" "D15"
			(at -3.225 0.001 90)
			(layer "F.SilkS")
			(effects
				(font
					(size 0.7 0.7)
					(thickness 0.15)
				)
			)
		)
		(property "Value" "PMEG3050EP,115"
			(at 0 2.4765 0)
			(layer "F.Fab")
			(effects
				(font
					(size 1 1)
					(thickness 0.15)
				)
			)
		)
		(property "Description" "Schottky Rectifier, 30 V, 5 A, Single, SOD-128, 2 Pins, 360 mV"
			(at 0 0 0)
			(layer "F.Fab")
			(hide yes)
			(effects
				(font
					(size 1.27 1.27)
					(thickness 0.15)
				)
			)
		)
		(property "Author" "Antmicro"
			(at 0 0 0)
			(layer "F.Fab")
			(hide yes)
			(effects
				(font
					(size 1 1)
					(thickness 0.15)
				)
			)
		)
		(property "DNP" "DNP"
			(at 0 0 0)
			(layer "F.Fab")
			(hide yes)
			(effects
				(font
					(size 1 1)
					(thickness 0.15)
				)
			)
		)
		(property "License" "Apache-2.0"
			(at 0 0 0)
			(layer "F.Fab")
			(hide yes)
			(effects
				(font
					(size 1 1)
					(thickness 0.15)
				)
			)
		)
		(property "MPN" "PMEG3050EP,115"
			(at 0 0 0)
			(layer "F.Fab")
			(hide yes)
			(effects
				(font
					(size 1 1)
					(thickness 0.15)
				)
			)
		)
		(property "Manufacturer" "Nexperia"
			(at 0 0 0)
			(layer "F.Fab")
			(hide yes)
			(effects
				(font
					(size 1 1)
					(thickness 0.15)
				)
			)
		)
		(property "dnp" ""
			(at 0 0 0)
			(layer "F.Fab")
			(hide yes)
			(effects
				(font
					(size 1 1)
					(thickness 0.15)
				)
			)
		)
		(property "exclude_from_bom" ""
			(at 0 0 0)
			(layer "F.Fab")
			(hide yes)
			(effects
				(font
					(size 1 1)
					(thickness 0.15)
				)
			)
		)
		(sheetname "Power supply")
		(sheetfile "power-supply.kicad_sch")
		(attr smd exclude_from_bom)
		(fp_line
			(start -2.121 -1.474)
			(end -2.121 -1.287)
			(stroke
				(width 0.15)
				(type solid)
			)
			(layer "F.SilkS")
		)
		(fp_line
			(start -2.121 1.284)
			(end -2.121 1.473)
			(stroke
				(width 0.15)
				(type solid)
			)
			(layer "F.SilkS")
		)
		(fp_line
			(start -2.121 1.473)
			(end 2.12 1.473)
			(stroke
				(width 0.15)
				(type solid)
			)
			(layer "F.SilkS")
		)
		(fp_line
			(start -1.6 -1.4)
			(end -1.6 1.4)
			(stroke
				(width 0.12)
				(type solid)
			)
			(layer "F.SilkS")
		)
		(fp_line
			(start 2.12 -1.474)
			(end -2.121 -1.474)
			(stroke
				(width 0.15)
				(type solid)
			)
			(layer "F.SilkS")
		)
		(fp_line
			(start 2.12 -1.287)
			(end 2.12 -1.474)
			(stroke
				(width 0.15)
				(type solid)
			)
			(layer "F.SilkS")
		)
		(fp_line
			(start 2.12 1.473)
			(end 2.12 1.284)
			(stroke
				(width 0.15)
				(type solid)
			)
			(layer "F.SilkS")
		)
		(fp_rect
			(start -2.8 -1.6)
			(end 2.8 1.6)
			(stroke
				(width 0.05)
				(type solid)
			)
			(fill no)
			(layer "F.CrtYd")
		)
		(fp_line
			(start -2.503 -0.954)
			(end -2.503 0.952)
			(stroke
				(width 0.15)
				(type solid)
			)
			(layer "F.Fab")
		)
		(fp_line
			(start -2.503 0.952)
			(end -1.994 0.952)
			(stroke
				(width 0.15)
				(type solid)
			)
			(layer "F.Fab")
		)
		(fp_line
			(start -1.994 -1.347)
			(end -1.994 1.346)
			(stroke
				(width 0.15)
				(type solid)
			)
			(layer "F.Fab")
		)
		(fp_line
			(start -1.994 -0.954)
			(end -2.503 -0.954)
			(stroke
				(width 0.15)
				(type solid)
			)
			(layer "F.Fab")
		)
		(fp_line
			(start -1.994 -0.675)
			(end -1.321 -1.347)
			(stroke
				(width 0.15)
				(type solid)
			)
			(layer "F.Fab")
		)
		(fp_line
			(start -1.994 0.673)
			(end -1.321 1.346)
			(stroke
				(width 0.15)
				(type solid)
			)
			(layer "F.Fab")
		)
		(fp_line
			(start -1.994 0.952)
			(end -1.994 -0.954)
			(stroke
				(width 0.15)
				(type solid)
			)
			(layer "F.Fab")
		)
		(fp_line
			(start -1.994 1.346)
			(end 1.993 1.346)
			(stroke
				(width 0.15)
				(type solid)
			)
			(layer "F.Fab")
		)
		(fp_line
			(start 1.993 -1.347)
			(end -1.994 -1.347)
			(stroke
				(width 0.15)
				(type solid)
			)
			(layer "F.Fab")
		)
		(fp_line
			(start 1.993 -0.954)
			(end 1.993 0.952)
			(stroke
				(width 0.15)
				(type solid)
			)
			(layer "F.Fab")
		)
		(fp_line
			(start 1.993 0.952)
			(end 2.5 0.952)
			(stroke
				(width 0.15)
				(type solid)
			)
			(layer "F.Fab")
		)
		(fp_line
			(start 1.993 1.346)
			(end 1.993 -1.347)
			(stroke
				(width 0.15)
				(type solid)
			)
			(layer "F.Fab")
		)
		(fp_line
			(start 2.5 -0.954)
			(end 1.993 -0.954)
			(stroke
				(width 0.15)
				(type solid)
			)
			(layer "F.Fab")
		)
		(fp_line
			(start 2.5 0.952)
			(end 2.5 -0.954)
			(stroke
				(width 0.15)
				(type solid)
			)
			(layer "F.Fab")
		)
		(pad "1" smd rect
			(at -2.298 0)
			(size 0.8096 1.905)
			(layers "F.Cu" "F.Mask" "F.Paste")
			(net 702 "VDC")
			(pinfunction "1")
			(pintype "passive")
		)
		(pad "2" smd rect
			(at 2.297 0)
			(size 0.8096 1.905)
			(layers "F.Cu" "F.Mask" "F.Paste")
			(net 4 "/Power supply/DC_IN")
			(pinfunction "2")
			(pintype "passive")
		)
	)
	(footprint "antmicro-footprints:C_0402_1005Metric"
		(layer "F.Cu")
		(at 166.7 140 180)
		(descr "Capacitor SMD 0402")
		(tags "capacitor SMD 0402")
		(property "Reference" "C390"
			(at -0.8 -0.35 180)
			(layer "F.SilkS")
			(effects
				(font
					(size 0.7 0.7)
					(thickness 0.15)
				)
				(justify left bottom)
			)
		)
		(property "Value" "C_100n_0402"
			(at 0 1.169 180)
			(layer "F.Fab")
			(effects
				(font
					(size 0.7 0.7)
					(thickness 0.15)
				)
				(justify left bottom)
			)
		)
		(property "Description" "SMD Multilayer Ceramic Capacitor, 0.1 µF, 50 V, 0402 [1005 Metric], ± 10%, X5R, GRM Series"
			(at 0 0 180)
			(layer "F.Fab")
			(hide yes)
			(effects
				(font
					(size 1.27 1.27)
					(thickness 0.15)
				)
			)
		)
		(property "Author" "Antmicro"
			(at 333.4 280 0)
			(layer "F.Fab")
			(hide yes)
			(effects
				(font
					(size 1 1)
					(thickness 0.15)
				)
			)
		)
		(property "Dielectric" "X5R"
			(at 333.4 280 0)
			(layer "F.Fab")
			(hide yes)
			(effects
				(font
					(size 1 1)
					(thickness 0.15)
				)
			)
		)
		(property "License" "Apache-2.0"
			(at 333.4 280 0)
			(layer "F.Fab")
			(hide yes)
			(effects
				(font
					(size 1 1)
					(thickness 0.15)
				)
			)
		)
		(property "MPN" "GRM155R61H104KE14D"
			(at 333.4 280 0)
			(layer "F.Fab")
			(hide yes)
			(effects
				(font
					(size 1 1)
					(thickness 0.15)
				)
			)
		)
		(property "Manufacturer" "Murata"
			(at 333.4 280 0)
			(layer "F.Fab")
			(hide yes)
			(effects
				(font
					(size 1 1)
					(thickness 0.15)
				)
			)
		)
		(property "Val" "100n"
			(at 333.4 280 0)
			(layer "F.Fab")
			(hide yes)
			(effects
				(font
					(size 1 1)
					(thickness 0.15)
				)
			)
		)
		(property "Voltage" "50V"
			(at 333.4 280 0)
			(layer "F.Fab")
			(hide yes)
			(effects
				(font
					(size 1 1)
					(thickness 0.15)
				)
			)
		)
		(sheetname "DRAM + SRAM")
		(sheetfile "ram.kicad_sch")
		(attr smd)
		(fp_rect
			(start -0.925 -0.47)
			(end 0.925 0.47)
			(stroke
				(width 0.05)
				(type default)
			)
			(fill no)
			(layer "F.CrtYd")
		)
		(fp_line
			(start 0.504 0.248)
			(end -0.494 0.248)
			(stroke
				(width 0.15)
				(type solid)
			)
			(layer "F.Fab")
		)
		(fp_line
			(start 0.504 -0.25)
			(end 0.504 0.248)
			(stroke
				(width 0.15)
				(type solid)
			)
			(layer "F.Fab")
		)
		(fp_line
			(start -0.494 0.248)
			(end -0.494 -0.25)
			(stroke
				(width 0.15)
				(type solid)
			)
			(layer "F.Fab")
		)
		(fp_line
			(start -0.494 -0.25)
			(end 0.504 -0.25)
			(stroke
				(width 0.15)
				(type solid)
			)
			(layer "F.Fab")
		)
		(pad "1" smd roundrect
			(at -0.48 0 180)
			(size 0.59 0.64)
			(layers "F.Cu" "F.Mask" "F.Paste")
			(roundrect_rratio 0.25)
			(net 1 "GND")
			(pintype "passive")
		)
		(pad "2" smd roundrect
			(at 0.48 0 180)
			(size 0.59 0.64)
			(layers "F.Cu" "F.Mask" "F.Paste")
			(roundrect_rratio 0.25)
			(net 25 "+1V35")
			(pintype "passive")
		)
	)
)
